# T6G (Grand Teton) — schematic netlist excerpt (pin names and nets, part order shuffled) for the footprints in the layout excerpt that follows; sources: Cadence DE-HDL packaged netlist, KiCad conversion of 04192023_DAF0TMB3IC0_F0TG_MB_C_brd_V02_OCP.brd

R1630  Q_RES  1K 1% CHIP  pkg 0402LF  page 172 : A = PVDD18_S5_P0 ; B = HDT_HDR_DBREQ_R_N
R1344  Q_RES  33.2 1% CHIP  pkg 0402LF  page 251 : A = SMB_INA230_3V3AUX_SCL ; B = SMB_INA230_6_3V3AUX_SCL_R

(kicad_pcb
	(version 20260206)
	(generator "pcbnew")
	(generator_version "10.0")
	(general
		(thickness 1.6)
		(legacy_teardrops no)
	)
	(paper "A4")
	(title_block
		(title "04192023_DAF0TMB3IC0_F0TG_MB_C_brd_V02_OCP.brd")
		(comment 1 "Grand Teton / footprints 4436-4437 of 8354")
	)
	(layers
		(0 "F.Cu" signal "TOP")
		(4 "In1.Cu" signal "GND")
		(6 "In2.Cu" signal "IN1")
		(8 "In3.Cu" signal "GND1")
		(10 "In4.Cu" signal "IN2")
		(12 "In5.Cu" signal "GND2")
		(14 "In6.Cu" signal "IN3")
		(16 "In7.Cu" signal "GND3")
		(18 "In8.Cu" signal "VCC")
		(20 "In9.Cu" signal "VCC1")
		(22 "In10.Cu" signal "GND4")
		(24 "In11.Cu" signal "IN4")
		(26 "In12.Cu" signal "GND5")
		(28 "In13.Cu" signal "IN5")
		(30 "In14.Cu" signal "GND6")
		(32 "In15.Cu" signal "IN6")
		(34 "In16.Cu" signal "GND7")
		(2 "B.Cu" signal "BOTTOM")
		(9 "F.Adhes" user "F.Adhesive")
		(11 "B.Adhes" user "B.Adhesive")
		(13 "F.Paste" user "Package Geometry/Pastemask Top")
		(15 "B.Paste" user "Package Geometry/Pastemask Bottom")
		(5 "F.SilkS" user "Ref Des/Silkscreen Top")
		(7 "B.SilkS" user "Ref Des/Silkscreen Bottom")
		(1 "F.Mask" user "Board Geometry/Soldermask Top")
		(3 "B.Mask" user "Board Geometry/Soldermask Bottom")
		(17 "Dwgs.User" user "User.Drawings")
		(19 "Cmts.User" user "User.Comments")
		(21 "Eco1.User" user "User.Eco1")
		(23 "Eco2.User" user "User.Eco2")
		(25 "Edge.Cuts" user "Board Geometry/Outline")
		(27 "Margin" user)
		(31 "F.CrtYd" user "Package Geometry/Place Bound Top")
		(29 "B.CrtYd" user "Package Geometry/Place Bound Bottom")
		(35 "F.Fab" user "Ref Des/Assembly Top")
		(33 "B.Fab" user "Ref Des/Assembly Bottom")
	)
	(footprint ""
		(layer "F.Cu")
		(at 298.704 -108.966 -90)
		(property "Reference" "R1344"
			(at 0 0 270)
			(layer "F.SilkS")
			(hide yes)
			(effects
				(font
					(size 1.27 1.27)
				)
			)
		)
		(property "Value" ""
			(at 0 0 270)
			(layer "F.Fab")
			(effects
				(font
					(size 1.27 1.27)
				)
			)
		)
		(duplicate_pad_numbers_are_jumpers no)
		(fp_line
			(start -0.7874 0.4064)
			(end -0.7874 -0.4064)
			(stroke
				(width 0.1524)
				(type default)
			)
			(layer "F.SilkS")
		)
		(fp_line
			(start 0.7874 0.4064)
			(end -0.7874 0.4064)
			(stroke
				(width 0.1524)
				(type default)
			)
			(layer "F.SilkS")
		)
		(fp_line
			(start -0.7874 -0.4064)
			(end 0.7874 -0.4064)
			(stroke
				(width 0.1524)
				(type default)
			)
			(layer "F.SilkS")
		)
		(fp_line
			(start 0.7874 -0.4064)
			(end 0.7874 0.4064)
			(stroke
				(width 0.1524)
				(type default)
			)
			(layer "F.SilkS")
		)
		(fp_line
			(start -0.67945 0.3048)
			(end -0.67945 -0.305054)
			(stroke
				(width 0.1)
				(type default)
			)
			(layer "F.Fab")
		)
		(fp_line
			(start -0.12065 0.3048)
			(end -0.67945 0.3048)
			(stroke
				(width 0.1)
				(type default)
			)
			(layer "F.Fab")
		)
		(fp_line
			(start 0.120396 0.3048)
			(end 0.120396 0.2794)
			(stroke
				(width 0.1)
				(type default)
			)
			(layer "F.Fab")
		)
		(fp_line
			(start 0.67945 0.3048)
			(end 0.120396 0.3048)
			(stroke
				(width 0.1)
				(type default)
			)
			(layer "F.Fab")
		)
		(fp_line
			(start -0.12065 0.2794)
			(end -0.12065 0.3048)
			(stroke
				(width 0.1)
				(type default)
			)
			(layer "F.Fab")
		)
		(fp_line
			(start 0.120396 0.2794)
			(end -0.12065 0.2794)
			(stroke
				(width 0.1)
				(type default)
			)
			(layer "F.Fab")
		)
		(fp_line
			(start -0.12065 -0.2794)
			(end 0.12065 -0.2794)
			(stroke
				(width 0.1)
				(type default)
			)
			(layer "F.Fab")
		)
		(fp_line
			(start 0.12065 -0.2794)
			(end 0.12065 -0.3048)
			(stroke
				(width 0.1)
				(type default)
			)
			(layer "F.Fab")
		)
		(fp_line
			(start 0.12065 -0.3048)
			(end 0.67945 -0.3048)
			(stroke
				(width 0.1)
				(type default)
			)
			(layer "F.Fab")
		)
		(fp_line
			(start 0.67945 -0.3048)
			(end 0.67945 0.3048)
			(stroke
				(width 0.1)
				(type default)
			)
			(layer "F.Fab")
		)
		(fp_line
			(start -0.67945 -0.305054)
			(end -0.12065 -0.305054)
			(stroke
				(width 0.1)
				(type default)
			)
			(layer "F.Fab")
		)
		(fp_line
			(start -0.12065 -0.305054)
			(end -0.12065 -0.2794)
			(stroke
				(width 0.1)
				(type default)
			)
			(layer "F.Fab")
		)
		(pad "1" smd circle
			(at -0.40005 0 270)
			(size 0 0)
			(layers "F.Cu" "F.Mask" "F.Paste")
			(net "SMB_INA230_3V3AUX_SCL")
		)
		(pad "2" smd circle
			(at 0.40005 0 270)
			(size 0 0)
			(layers "F.Cu" "F.Mask" "F.Paste")
			(net "SMB_INA230_6_3V3AUX_SCL_R")
		)
	)
	(footprint ""
		(layer "F.Cu")
		(at 386.211826 -60.456318 180)
		(property "Reference" "R1630"
			(at 0 0 180)
			(layer "F.SilkS")
			(hide yes)
			(effects
				(font
					(size 1.27 1.27)
				)
			)
		)
		(property "Value" ""
			(at 0 0 180)
			(layer "F.Fab")
			(effects
				(font
					(size 1.27 1.27)
				)
			)
		)
		(duplicate_pad_numbers_are_jumpers no)
		(fp_line
			(start 0.7874 0.4064)
			(end -0.7874 0.4064)
			(stroke
				(width 0.1524)
				(type default)
			)
			(layer "F.SilkS")
		)
		(fp_line
			(start 0.7874 -0.4064)
			(end 0.7874 0.4064)
			(stroke
				(width 0.1524)
				(type default)
			)
			(layer "F.SilkS")
		)
		(fp_line
			(start -0.7874 0.4064)
			(end -0.7874 -0.4064)
			(stroke
				(width 0.1524)
				(type default)
			)
			(layer "F.SilkS")
		)
		(fp_line
			(start -0.7874 -0.4064)
			(end 0.7874 -0.4064)
			(stroke
				(width 0.1524)
				(type default)
			)
			(layer "F.SilkS")
		)
		(fp_line
			(start 0.67945 0.3048)
			(end 0.120396 0.3048)
			(stroke
				(width 0.1)
				(type default)
			)
			(layer "F.Fab")
		)
		(fp_line
			(start 0.67945 -0.3048)
			(end 0.67945 0.3048)
			(stroke
				(width 0.1)
				(type default)
			)
			(layer "F.Fab")
		)
		(fp_line
			(start 0.12065 -0.2794)
			(end 0.12065 -0.3048)
			(stroke
				(width 0.1)
				(type default)
			)
			(layer "F.Fab")
		)
		(fp_line
			(start 0.12065 -0.3048)
			(end 0.67945 -0.3048)
			(stroke
				(width 0.1)
				(type default)
			)
			(layer "F.Fab")
		)
		(fp_line
			(start 0.120396 0.3048)
			(end 0.120396 0.2794)
			(stroke
				(width 0.1)
				(type default)
			)
			(layer "F.Fab")
		)
		(fp_line
			(start 0.120396 0.2794)
			(end -0.12065 0.2794)
			(stroke
				(width 0.1)
				(type default)
			)
			(layer "F.Fab")
		)
		(fp_line
			(start -0.12065 0.3048)
			(end -0.67945 0.3048)
			(stroke
				(width 0.1)
				(type default)
			)
			(layer "F.Fab")
		)
		(fp_line
			(start -0.12065 0.2794)
			(end -0.12065 0.3048)
			(stroke
				(width 0.1)
				(type default)
			)
			(layer "F.Fab")
		)
		(fp_line
			(start -0.12065 -0.2794)
			(end 0.12065 -0.2794)
			(stroke
				(width 0.1)
				(type default)
			)
			(layer "F.Fab")
		)
		(fp_line
			(start -0.12065 -0.305054)
			(end -0.12065 -0.2794)
			(stroke
				(width 0.1)
				(type default)
			)
			(layer "F.Fab")
		)
		(fp_line
			(start -0.67945 0.3048)
			(end -0.67945 -0.305054)
			(stroke
				(width 0.1)
				(type default)
			)
			(layer "F.Fab")
		)
		(fp_line
			(start -0.67945 -0.305054)
			(end -0.12065 -0.305054)
			(stroke
				(width 0.1)
				(type default)
			)
			(layer "F.Fab")
		)
		(pad "1" smd circle
			(at -0.40005 0 180)
			(size 0 0)
			(layers "F.Cu" "F.Mask" "F.Paste")
			(net "PVDD18_S5_P0")
		)
		(pad "2" smd circle
			(at 0.40005 0 180)
			(size 0 0)
			(layers "F.Cu" "F.Mask" "F.Paste")
			(net "HDT_HDR_DBREQ_R_N")
		)
	)
)
